# TIMECARD (Time Appliance Project (Time Card)) — schematic netlist excerpt (pin names and nets, part order shuffled) for the footprints in the layout excerpt that follows; sources: Cadence DE-HDL packaged netlist, KiCad conversion of R4006-B0001-02_R01.brd

U30  TS3A5018PWR_TSSOP16  pkg SOP16_173_P0256  page 24
  \in\  = MUX1_SEL
  NC1  = FT4232_FPGA_TCK
  NO1  = FT4232_SPI_CLK
  COM1  = FT4232_TCK_SCLK
  NC2  = FT4232_FPGA_TDI
  NO2  = FT4232_SPI_MOSI
  COM2  = FT4232_TDI_MOSI
  GND  = SG
  COM3  = FT4232_TDO_MISO
  NO3  = FT4232_SPI_MISO
  NC3  = FT4232_FPGA_TDO
  COM4  = FT4232_TMS_SPICS_N
  NO4  = FT4232_SPI_CS_N
  NC4  = FT4232_FPGA_TMS
  \en*\  = UNNAMED_524_POWERMOS3PNCHV1_I44
  V_P  = XP3R3V_FPGA

(kicad_pcb
	(version 20260206)
	(generator "pcbnew")
	(generator_version "10.0")
	(general
		(thickness 1.6)
		(legacy_teardrops no)
	)
	(paper "A4")
	(title_block
		(title "timecard-production-celestica-r4006 — R4006-B0001-02_R01.brd")
		(comment 1 "Time Appliance Project (Time Card) / footprints 317-317 of 1113")
	)
	(layers
		(0 "F.Cu" signal "TOP")
		(4 "In1.Cu" signal "L02_GND1")
		(6 "In2.Cu" signal "L03_SIG1")
		(8 "In3.Cu" signal "L04_GND2")
		(10 "In4.Cu" signal "L05_VCC1")
		(12 "In5.Cu" signal "L06_VCC2")
		(14 "In6.Cu" signal "L07_GND3")
		(16 "In7.Cu" signal "L08_SIG2")
		(18 "In8.Cu" signal "L09_GND4")
		(2 "B.Cu" signal "BOTTOM")
		(9 "F.Adhes" user "F.Adhesive")
		(11 "B.Adhes" user "B.Adhesive")
		(13 "F.Paste" user "Package Geometry/Pastemask Top")
		(15 "B.Paste" user "Package Geometry/Pastemask Bottom")
		(5 "F.SilkS" user "Ref Des/Silkscreen Top")
		(7 "B.SilkS" user "Ref Des/Silkscreen Bottom")
		(1 "F.Mask" user "Board Geometry/Soldermask Top")
		(3 "B.Mask" user "Board Geometry/Soldermask Bottom")
		(17 "Dwgs.User" user "User.Drawings")
		(19 "Cmts.User" user "User.Comments")
		(21 "Eco1.User" user "User.Eco1")
		(23 "Eco2.User" user "User.Eco2")
		(25 "Edge.Cuts" user "Board Geometry/Outline")
		(27 "Margin" user)
		(31 "F.CrtYd" user "Package Geometry/Place Bound Top")
		(29 "B.CrtYd" user "Package Geometry/Place Bound Bottom")
		(35 "F.Fab" user "Ref Des/Assembly Top")
		(33 "B.Fab" user "Ref Des/Assembly Bottom")
	)
	(footprint ""
		(layer "F.Cu")
		(at 105.537 -93.345)
		(property "Reference" "U30"
			(at -0.254 -3.26263 0)
			(unlocked yes)
			(layer "F.SilkS")
			(effects
				(font
					(size 0.7874 0.5842)
					(thickness 0.1524)
				)
			)
		)
		(property "Value" ""
			(at 0 0 0)
			(layer "F.Fab")
			(effects
				(font
					(size 1.27 1.27)
				)
			)
		)
		(property "Device Type" "TS3A5018PWR_TSSOP16-G220-10324A"
			(at 0 0.924306 0)
			(unlocked yes)
			(layer "F.Fab")
			(hide yes)
			(effects
				(font
					(size 0.7874 0.5842)
					(thickness 0.000001)
				)
			)
		)
		(property "User Part Number" "PARTNUM*"
			(at 0.254 1.940306 0)
			(unlocked yes)
			(layer "Cmts.User")
			(hide yes)
			(effects
				(font
					(size 0.7874 0.5842)
					(thickness 0.000001)
				)
			)
		)
		(duplicate_pad_numbers_are_jumpers no)
		(fp_line
			(start -4.0767 -2.7559)
			(end 4.0767 -2.7559)
			(stroke
				(width 0.1)
				(type default)
			)
			(layer "F.SilkS")
		)
		(fp_line
			(start -4.0767 2.7559)
			(end -4.0767 -2.7559)
			(stroke
				(width 0.1)
				(type default)
			)
			(layer "F.SilkS")
		)
		(fp_line
			(start 4.0767 -2.7559)
			(end 4.0767 2.7559)
			(stroke
				(width 0.1)
				(type default)
			)
			(layer "F.SilkS")
		)
		(fp_line
			(start 4.0767 2.7559)
			(end -4.0767 2.7559)
			(stroke
				(width 0.1)
				(type default)
			)
			(layer "F.SilkS")
		)
		(fp_poly
			(pts
				(arc
					(start -4.3815 -2.2225)
					(mid -5.1435 -2.2225)
					(end -4.3815 -2.2225)
				)
			)
			(stroke
				(width 0)
				(type default)
			)
			(fill yes)
			(layer "F.SilkS")
		)
		(fp_rect
			(start -4.3307 3.0099)
			(end 4.3307 -3.0099)
			(stroke
				(width 0)
				(type default)
			)
			(fill no)
			(layer "F.CrtYd")
		)
		(fp_line
			(start -2.1971 -2.5019)
			(end 2.1971 -2.5019)
			(stroke
				(width 0.1)
				(type default)
			)
			(layer "F.Fab")
		)
		(fp_line
			(start -2.1971 2.5019)
			(end -2.1971 -2.5019)
			(stroke
				(width 0.1)
				(type default)
			)
			(layer "F.Fab")
		)
		(fp_line
			(start 2.1971 -2.5019)
			(end 2.1971 2.5019)
			(stroke
				(width 0.1)
				(type default)
			)
			(layer "F.Fab")
		)
		(fp_line
			(start 2.1971 2.5019)
			(end -2.1971 2.5019)
			(stroke
				(width 0.1)
				(type default)
			)
			(layer "F.Fab")
		)
		(fp_poly
			(pts
				(arc
					(start -1.114298 -1.942084)
					(mid -1.914398 -1.942084)
					(end -1.114298 -1.942084)
				)
			)
			(stroke
				(width 0)
				(type default)
			)
			(fill yes)
			(layer "F.Fab")
		)
		(fp_text user "8"
			(at -4.699 2.57937 0)
			(unlocked yes)
			(layer "F.SilkS")
			(effects
				(font
					(size 0.7874 0.5842)
					(thickness 0.1524)
				)
			)
		)
		(fp_text user "16"
			(at 4.572 -2.50825 0)
			(unlocked yes)
			(layer "F.SilkS")
			(effects
				(font
					(size 0.635 0.4064)
					(thickness 0.1524)
				)
			)
		)
		(fp_text user "9"
			(at 4.699 2.83337 0)
			(unlocked yes)
			(layer "F.SilkS")
			(effects
				(font
					(size 0.7874 0.5842)
					(thickness 0.1524)
				)
			)
		)
		(fp_text user "8"
			(at -4.572 2.18567 0)
			(unlocked yes)
			(layer "F.Fab")
			(effects
				(font
					(size 0.7874 0.5842)
					(thickness 0.1524)
				)
			)
		)
		(fp_text user "9"
			(at 4.5466 2.31267 0)
			(unlocked yes)
			(layer "F.Fab")
			(effects
				(font
					(size 0.7874 0.5842)
					(thickness 0.1524)
				)
			)
		)
		(fp_text user "16"
			(at 4.572 -3.00863 0)
			(unlocked yes)
			(layer "F.Fab")
			(effects
				(font
					(size 0.7874 0.5842)
					(thickness 0.1524)
				)
			)
		)
		(pad "1" smd rect
			(at -3.0353 -2.275078 90)
			(size 0.3556 1.5748)
			(layers "F.Cu" "F.Mask" "F.Paste")
			(net "MUX1_SEL")
		)
		(pad "2" smd rect
			(at -3.0353 -1.625092 90)
			(size 0.3556 1.5748)
			(layers "F.Cu" "F.Mask" "F.Paste")
			(net "FT4232_FPGA_TCK")
		)
		(pad "3" smd rect
			(at -3.0353 -0.975106 90)
			(size 0.3556 1.5748)
			(layers "F.Cu" "F.Mask" "F.Paste")
			(net "FT4232_SPI_CLK")
		)
		(pad "4" smd rect
			(at -3.0353 -0.32512 90)
			(size 0.3556 1.5748)
			(layers "F.Cu" "F.Mask" "F.Paste")
			(net "FT4232_TCK_SCLK")
		)
		(pad "5" smd rect
			(at -3.0353 0.32512 90)
			(size 0.3556 1.5748)
			(layers "F.Cu" "F.Mask" "F.Paste")
			(net "FT4232_FPGA_TDI")
		)
		(pad "6" smd rect
			(at -3.0353 0.975106 90)
			(size 0.3556 1.5748)
			(layers "F.Cu" "F.Mask" "F.Paste")
			(net "FT4232_SPI_MOSI")
		)
		(pad "7" smd rect
			(at -3.0353 1.625092 90)
			(size 0.3556 1.5748)
			(layers "F.Cu" "F.Mask" "F.Paste")
			(net "FT4232_TDI_MOSI")
		)
		(pad "8" smd rect
			(at -3.0353 2.275078 90)
			(size 0.3556 1.5748)
			(layers "F.Cu" "F.Mask" "F.Paste")
			(net "SG")
		)
		(pad "9" smd rect
			(at 3.0353 2.275078 90)
			(size 0.3556 1.5748)
			(layers "F.Cu" "F.Mask" "F.Paste")
			(net "FT4232_TDO_MISO")
		)
		(pad "10" smd rect
			(at 3.0353 1.625092 90)
			(size 0.3556 1.5748)
			(layers "F.Cu" "F.Mask" "F.Paste")
			(net "FT4232_SPI_MISO")
		)
		(pad "11" smd rect
			(at 3.0353 0.975106 90)
			(size 0.3556 1.5748)
			(layers "F.Cu" "F.Mask" "F.Paste")
			(net "FT4232_FPGA_TDO")
		)
		(pad "12" smd rect
			(at 3.0353 0.32512 90)
			(size 0.3556 1.5748)
			(layers "F.Cu" "F.Mask" "F.Paste")
			(net "FT4232_TMS_SPICS_N")
		)
		(pad "13" smd rect
			(at 3.0353 -0.32512 90)
			(size 0.3556 1.5748)
			(layers "F.Cu" "F.Mask" "F.Paste")
			(net "FT4232_SPI_CS_N")
		)
		(pad "14" smd rect
			(at 3.0353 -0.975106 90)
			(size 0.3556 1.5748)
			(layers "F.Cu" "F.Mask" "F.Paste")
			(net "FT4232_FPGA_TMS")
		)
		(pad "15" smd rect
			(at 3.0353 -1.625092 90)
			(size 0.3556 1.5748)
			(layers "F.Cu" "F.Mask" "F.Paste")
			(net "UNNAMED_524_POWERMOS3PNCHV1_I44")
		)
		(pad "16" smd rect
			(at 3.0353 -2.275078 90)
			(size 0.3556 1.5748)
			(layers "F.Cu" "F.Mask" "F.Paste")
			(net "XP3R3V_FPGA")
		)
	)
)
